# SCM (Grand Teton) — schematic netlist excerpt (pin names and nets, part order shuffled) for the footprints in the layout excerpt that follows; sources: Cadence DE-HDL packaged netlist, KiCad conversion of 12092022_DA0F0TMDCD0_F0T_Management_Board_D_brd_V3_OCP.brd

C309  Q_CAP  0.1UF 25V 10% X7R  pkg 0402  page 15 : A = P1V2_SENSOR ; B = GND
R235  Q_RES  2.74K 1% CHIP  pkg 0402LF  page 16 : A = GND ; B = A_BMC_DACREST

(kicad_pcb
	(version 20260206)
	(generator "pcbnew")
	(generator_version "10.0")
	(general
		(thickness 1.6)
		(legacy_teardrops no)
	)
	(paper "A4")
	(title_block
		(title "12092022_DA0F0TMDCD0_F0T_Management_Board_D_brd_V3_OCP.brd")
		(comment 1 "Grand Teton / footprints 735-736 of 1440")
	)
	(layers
		(0 "F.Cu" signal "TOP")
		(4 "In1.Cu" signal "GND")
		(6 "In2.Cu" signal "IN1")
		(8 "In3.Cu" signal "GND1")
		(10 "In4.Cu" signal "IN2")
		(12 "In5.Cu" signal "VCC")
		(14 "In6.Cu" signal "VCC1")
		(16 "In7.Cu" signal "IN3")
		(18 "In8.Cu" signal "GND2")
		(20 "In9.Cu" signal "IN4")
		(22 "In10.Cu" signal "GND3")
		(2 "B.Cu" signal "BOTTOM")
		(9 "F.Adhes" user "F.Adhesive")
		(11 "B.Adhes" user "B.Adhesive")
		(13 "F.Paste" user "Package Geometry/Pastemask Top")
		(15 "B.Paste" user "Package Geometry/Pastemask Bottom")
		(5 "F.SilkS" user "Ref Des/Silkscreen Top")
		(7 "B.SilkS" user "Ref Des/Silkscreen Bottom")
		(1 "F.Mask" user "Board Geometry/Soldermask Top")
		(3 "B.Mask" user "Board Geometry/Soldermask Bottom")
		(17 "Dwgs.User" user "User.Drawings")
		(19 "Cmts.User" user "User.Comments")
		(21 "Eco1.User" user "User.Eco1")
		(23 "Eco2.User" user "User.Eco2")
		(25 "Edge.Cuts" user "Board Geometry/Outline")
		(27 "Margin" user)
		(31 "F.CrtYd" user "Package Geometry/Place Bound Top")
		(29 "B.CrtYd" user "Package Geometry/Place Bound Bottom")
		(35 "F.Fab" user "Ref Des/Assembly Top")
		(33 "B.Fab" user "Ref Des/Assembly Bottom")
	)
	(footprint ""
		(layer "B.Cu")
		(at 56.173116 -74.242676 90)
		(property "Reference" "C309"
			(at 0 0 90)
			(layer "B.SilkS")
			(hide yes)
			(effects
				(font
					(size 1.27 1.27)
				)
				(justify mirror)
			)
		)
		(property "Value" ""
			(at 0 0 90)
			(layer "B.Fab")
			(effects
				(font
					(size 1.27 1.27)
				)
				(justify mirror)
			)
		)
		(duplicate_pad_numbers_are_jumpers no)
		(fp_line
			(start 0.7874 -0.4064)
			(end -0.7874 -0.4064)
			(stroke
				(width 0.1524)
				(type default)
			)
			(layer "B.SilkS")
		)
		(fp_line
			(start -0.7874 -0.4064)
			(end -0.7874 0.4064)
			(stroke
				(width 0.1524)
				(type default)
			)
			(layer "B.SilkS")
		)
		(fp_line
			(start 0.7874 0.4064)
			(end 0.7874 -0.4064)
			(stroke
				(width 0.1524)
				(type default)
			)
			(layer "B.SilkS")
		)
		(fp_line
			(start -0.7874 0.4064)
			(end 0.7874 0.4064)
			(stroke
				(width 0.1524)
				(type default)
			)
			(layer "B.SilkS")
		)
		(fp_line
			(start 0.67945 -0.305054)
			(end 0.12065 -0.305054)
			(stroke
				(width 0.1)
				(type default)
			)
			(layer "B.Fab")
		)
		(fp_line
			(start 0.12065 -0.305054)
			(end 0.12065 -0.2794)
			(stroke
				(width 0.1)
				(type default)
			)
			(layer "B.Fab")
		)
		(fp_line
			(start -0.12065 -0.3048)
			(end -0.67945 -0.3048)
			(stroke
				(width 0.1)
				(type default)
			)
			(layer "B.Fab")
		)
		(fp_line
			(start -0.67945 -0.3048)
			(end -0.67945 0.3048)
			(stroke
				(width 0.1)
				(type default)
			)
			(layer "B.Fab")
		)
		(fp_line
			(start 0.12065 -0.2794)
			(end -0.12065 -0.2794)
			(stroke
				(width 0.1)
				(type default)
			)
			(layer "B.Fab")
		)
		(fp_line
			(start -0.12065 -0.2794)
			(end -0.12065 -0.3048)
			(stroke
				(width 0.1)
				(type default)
			)
			(layer "B.Fab")
		)
		(fp_line
			(start 0.12065 0.2794)
			(end 0.12065 0.3048)
			(stroke
				(width 0.1)
				(type default)
			)
			(layer "B.Fab")
		)
		(fp_line
			(start -0.120396 0.2794)
			(end 0.12065 0.2794)
			(stroke
				(width 0.1)
				(type default)
			)
			(layer "B.Fab")
		)
		(fp_line
			(start 0.67945 0.3048)
			(end 0.67945 -0.305054)
			(stroke
				(width 0.1)
				(type default)
			)
			(layer "B.Fab")
		)
		(fp_line
			(start 0.12065 0.3048)
			(end 0.67945 0.3048)
			(stroke
				(width 0.1)
				(type default)
			)
			(layer "B.Fab")
		)
		(fp_line
			(start -0.120396 0.3048)
			(end -0.120396 0.2794)
			(stroke
				(width 0.1)
				(type default)
			)
			(layer "B.Fab")
		)
		(fp_line
			(start -0.67945 0.3048)
			(end -0.120396 0.3048)
			(stroke
				(width 0.1)
				(type default)
			)
			(layer "B.Fab")
		)
		(pad "1" smd circle
			(at 0.40005 0 270)
			(size 0 0)
			(layers "B.Cu" "B.Mask" "B.Paste")
			(net "P1V2_SENSOR")
		)
		(pad "2" smd circle
			(at -0.40005 0 270)
			(size 0 0)
			(layers "B.Cu" "B.Mask" "B.Paste")
			(net "GND")
		)
	)
	(footprint ""
		(layer "B.Cu")
		(at 43.1038 -62.1792 90)
		(property "Reference" "R235"
			(at 0 0 90)
			(layer "B.SilkS")
			(hide yes)
			(effects
				(font
					(size 1.27 1.27)
				)
				(justify mirror)
			)
		)
		(property "Value" ""
			(at 0 0 90)
			(layer "B.Fab")
			(effects
				(font
					(size 1.27 1.27)
				)
				(justify mirror)
			)
		)
		(duplicate_pad_numbers_are_jumpers no)
		(fp_line
			(start 0.7874 -0.4064)
			(end -0.7874 -0.4064)
			(stroke
				(width 0.1524)
				(type default)
			)
			(layer "B.SilkS")
		)
		(fp_line
			(start -0.7874 -0.4064)
			(end -0.7874 0.4064)
			(stroke
				(width 0.1524)
				(type default)
			)
			(layer "B.SilkS")
		)
		(fp_line
			(start 0.7874 0.4064)
			(end 0.7874 -0.4064)
			(stroke
				(width 0.1524)
				(type default)
			)
			(layer "B.SilkS")
		)
		(fp_line
			(start -0.7874 0.4064)
			(end 0.7874 0.4064)
			(stroke
				(width 0.1524)
				(type default)
			)
			(layer "B.SilkS")
		)
		(fp_line
			(start 0.67945 -0.305054)
			(end 0.12065 -0.305054)
			(stroke
				(width 0.1)
				(type default)
			)
			(layer "B.Fab")
		)
		(fp_line
			(start 0.12065 -0.305054)
			(end 0.12065 -0.2794)
			(stroke
				(width 0.1)
				(type default)
			)
			(layer "B.Fab")
		)
		(fp_line
			(start -0.12065 -0.3048)
			(end -0.67945 -0.3048)
			(stroke
				(width 0.1)
				(type default)
			)
			(layer "B.Fab")
		)
		(fp_line
			(start -0.67945 -0.3048)
			(end -0.67945 0.3048)
			(stroke
				(width 0.1)
				(type default)
			)
			(layer "B.Fab")
		)
		(fp_line
			(start 0.12065 -0.2794)
			(end -0.12065 -0.2794)
			(stroke
				(width 0.1)
				(type default)
			)
			(layer "B.Fab")
		)
		(fp_line
			(start -0.12065 -0.2794)
			(end -0.12065 -0.3048)
			(stroke
				(width 0.1)
				(type default)
			)
			(layer "B.Fab")
		)
		(fp_line
			(start 0.12065 0.2794)
			(end 0.12065 0.3048)
			(stroke
				(width 0.1)
				(type default)
			)
			(layer "B.Fab")
		)
		(fp_line
			(start -0.120396 0.2794)
			(end 0.12065 0.2794)
			(stroke
				(width 0.1)
				(type default)
			)
			(layer "B.Fab")
		)
		(fp_line
			(start 0.67945 0.3048)
			(end 0.67945 -0.305054)
			(stroke
				(width 0.1)
				(type default)
			)
			(layer "B.Fab")
		)
		(fp_line
			(start 0.12065 0.3048)
			(end 0.67945 0.3048)
			(stroke
				(width 0.1)
				(type default)
			)
			(layer "B.Fab")
		)
		(fp_line
			(start -0.120396 0.3048)
			(end -0.120396 0.2794)
			(stroke
				(width 0.1)
				(type default)
			)
			(layer "B.Fab")
		)
		(fp_line
			(start -0.67945 0.3048)
			(end -0.120396 0.3048)
			(stroke
				(width 0.1)
				(type default)
			)
			(layer "B.Fab")
		)
		(pad "1" smd circle
			(at 0.40005 0 270)
			(size 0 0)
			(layers "B.Cu" "B.Mask" "B.Paste")
			(net "GND")
		)
		(pad "2" smd circle
			(at -0.40005 0 270)
			(size 0 0)
			(layers "B.Cu" "B.Mask" "B.Paste")
			(net "A_BMC_DACREST")
		)
	)
)
